(kicad_pcb
	(version 20260206)
	(generator "pcbnew")
	(generator_version "10.0")
	(general
		(thickness 1.6)
		(legacy_teardrops no)
	)
	(paper "A4")
	(title_block
		(title "Bryce Canyon_SCC_16316-1_OCP.brd")
		(comment 1 "Bryce Canyon / footprints 570-574 of 1561")
	)
	(layers
		(0 "F.Cu" signal "TOP")
		(4 "In1.Cu" signal "L2GND")
		(6 "In2.Cu" signal "L3")
		(8 "In3.Cu" signal "L4VCC")
		(10 "In4.Cu" signal "L5VCC")
		(12 "In5.Cu" signal "L6")
		(14 "In6.Cu" signal "L7GND")
		(2 "B.Cu" signal "BOTTOM")
		(9 "F.Adhes" user "F.Adhesive")
		(11 "B.Adhes" user "B.Adhesive")
		(13 "F.Paste" user "Package Geometry/Pastemask Top")
		(15 "B.Paste" user "Package Geometry/Pastemask Bottom")
		(5 "F.SilkS" user "Ref Des/Silkscreen Top")
		(7 "B.SilkS" user "Ref Des/Silkscreen Bottom")
		(1 "F.Mask" user "Board Geometry/Soldermask Top")
		(3 "B.Mask" user "Board Geometry/Soldermask Bottom")
		(17 "Dwgs.User" user "User.Drawings")
		(19 "Cmts.User" user "User.Comments")
		(21 "Eco1.User" user "User.Eco1")
		(23 "Eco2.User" user "User.Eco2")
		(25 "Edge.Cuts" user "Board Geometry/Outline")
		(27 "Margin" user)
		(31 "F.CrtYd" user "Package Geometry/Place Bound Top")
		(29 "B.CrtYd" user "Package Geometry/Place Bound Bottom")
		(35 "F.Fab" user "Ref Des/Assembly Top")
		(33 "B.Fab" user "Ref Des/Assembly Bottom")
	)
	(footprint ""
		(layer "F.Cu")
		(at 74.4728 -81.7118 90)
		(property "Reference" "R583"
			(at 0 0 90)
			(layer "F.SilkS")
			(hide yes)
			(effects
				(font
					(size 1.27 1.27)
				)
			)
		)
		(property "Value" "0R2J-2-GP"
			(at 0.064008 -3.993896 90)
			(unlocked yes)
			(layer "F.Fab")
			(hide yes)
			(effects
				(font
					(size 1.016 1.016)
					(thickness 0.1524)
				)
			)
		)
		(property "Device Type" "R402H16"
			(at 0.064008 -5.517896 90)
			(unlocked yes)
			(layer "F.Fab")
			(hide yes)
			(effects
				(font
					(size 1.016 1.016)
					(thickness 0.1524)
				)
			)
		)
		(duplicate_pad_numbers_are_jumpers no)
		(fp_line
			(start 0.508 -0.9398)
			(end -0.508 -0.9398)
			(stroke
				(width 0.1524)
				(type default)
			)
			(layer "F.SilkS")
		)
		(fp_line
			(start -0.508 -0.9398)
			(end -0.508 0.9398)
			(stroke
				(width 0.1524)
				(type default)
			)
			(layer "F.SilkS")
		)
		(fp_rect
			(start -0.508 0.9398)
			(end 0.508 -0.9398)
			(stroke
				(width 0)
				(type default)
			)
			(fill no)
			(layer "F.CrtYd")
		)
		(fp_rect
			(start -0.508 0.9398)
			(end 0.508 -0.9398)
			(stroke
				(width 0)
				(type default)
			)
			(fill no)
			(layer "F.Fab")
		)
		(pad "1" smd custom
			(at 0 -0.4445 90)
			(size 0.1397 0.1397)
			(layers "F.Cu" "F.Mask" "F.Paste")
			(net "P1V8_E")
			(options
				(clearance outline)
				(anchor circle)
			)
			(primitives
				(gr_poly
					(pts
						(arc
							(start -0.1778 -0.2794)
							(mid -0.249642 -0.249642)
							(end -0.2794 -0.1778)
						)
						(arc
							(start -0.2794 0.1778)
							(mid -0.249642 0.249642)
							(end -0.1778 0.2794)
						)
						(arc
							(start 0.1778 0.2794)
							(mid 0.249642 0.249642)
							(end 0.2794 0.1778)
						)
						(arc
							(start 0.2794 -0.1778)
							(mid 0.249642 -0.249642)
							(end 0.1778 -0.2794)
						)
					)
					(width 0)
					(fill yes)
				)
			)
		)
		(pad "2" smd custom
			(at 0 0.4445 90)
			(size 0.1397 0.1397)
			(layers "F.Cu" "F.Mask" "F.Paste")
			(net "U118_VCC")
			(options
				(clearance outline)
				(anchor circle)
			)
			(primitives
				(gr_poly
					(pts
						(arc
							(start -0.1778 -0.2794)
							(mid -0.249642 -0.249642)
							(end -0.2794 -0.1778)
						)
						(arc
							(start -0.2794 0.1778)
							(mid -0.249642 0.249642)
							(end -0.1778 0.2794)
						)
						(arc
							(start 0.1778 0.2794)
							(mid 0.249642 0.249642)
							(end 0.2794 0.1778)
						)
						(arc
							(start 0.2794 -0.1778)
							(mid 0.249642 -0.249642)
							(end 0.1778 -0.2794)
						)
					)
					(width 0)
					(fill yes)
				)
			)
		)
	)
	(footprint ""
		(layer "F.Cu")
		(at 192.401952 -76.037694)
		(property "Reference" "C535"
			(at 0 0 0)
			(layer "F.SilkS")
			(hide yes)
			(effects
				(font
					(size 1.27 1.27)
				)
			)
		)
		(property "Value" "SCD1U16V2KX-3GP"
			(at 1.1811 -2.7051 0)
			(unlocked yes)
			(layer "F.Fab")
			(hide yes)
			(effects
				(font
					(size 1.016 1.016)
					(thickness 0.1524)
				)
			)
		)
		(property "Device Type" "C402H22"
			(at 1.1811 -4.2291 0)
			(unlocked yes)
			(layer "F.Fab")
			(hide yes)
			(effects
				(font
					(size 1.016 1.016)
					(thickness 0.1524)
				)
			)
		)
		(duplicate_pad_numbers_are_jumpers no)
		(fp_rect
			(start -0.4318 0.9525)
			(end 0.4318 -0.9525)
			(stroke
				(width 0)
				(type default)
			)
			(fill no)
			(layer "F.CrtYd")
		)
		(fp_rect
			(start -0.4318 0.9525)
			(end 0.4318 -0.9525)
			(stroke
				(width 0)
				(type default)
			)
			(fill no)
			(layer "F.Fab")
		)
		(pad "1" smd custom
			(at 0 -0.4445)
			(size 0.1524 0.1524)
			(layers "F.Cu" "F.Mask" "F.Paste")
			(net "GND")
			(options
				(clearance outline)
				(anchor circle)
			)
			(primitives
				(gr_poly
					(pts
						(arc
							(start 0.3048 -0.2032)
							(mid 0.275042 -0.275042)
							(end 0.2032 -0.3048)
						)
						(arc
							(start -0.2032 -0.3048)
							(mid -0.275042 -0.275042)
							(end -0.3048 -0.2032)
						)
						(arc
							(start -0.3048 0.2032)
							(mid -0.275042 0.275042)
							(end -0.2032 0.3048)
						)
						(arc
							(start 0.2032 0.3048)
							(mid 0.275042 0.275042)
							(end 0.3048 0.2032)
						)
					)
					(width 0)
					(fill yes)
				)
			)
		)
		(pad "2" smd custom
			(at 0 0.4445)
			(size 0.1524 0.1524)
			(layers "F.Cu" "F.Mask" "F.Paste")
			(net "P3V3")
			(options
				(clearance outline)
				(anchor circle)
			)
			(primitives
				(gr_poly
					(pts
						(arc
							(start 0.3048 -0.2032)
							(mid 0.275042 -0.275042)
							(end 0.2032 -0.3048)
						)
						(arc
							(start -0.2032 -0.3048)
							(mid -0.275042 -0.275042)
							(end -0.3048 -0.2032)
						)
						(arc
							(start -0.3048 0.2032)
							(mid -0.275042 0.275042)
							(end -0.2032 0.3048)
						)
						(arc
							(start 0.2032 0.3048)
							(mid 0.275042 0.275042)
							(end 0.3048 0.2032)
						)
					)
					(width 0)
					(fill yes)
				)
			)
		)
	)
	(footprint ""
		(layer "F.Cu")
		(at 70.485 -60.833 90)
		(property "Reference" "L12"
			(at 0 0 90)
			(layer "F.SilkS")
			(hide yes)
			(effects
				(font
					(size 1.27 1.27)
				)
			)
		)
		(property "Value" "MPZ2012S300AT-GP"
			(at 0 -4.2418 90)
			(unlocked yes)
			(layer "F.Fab")
			(hide yes)
			(effects
				(font
					(size 1.016 1.016)
					(thickness 0.1524)
				)
			)
		)
		(property "Device Type" "L805H42"
			(at 0 -5.7912 90)
			(unlocked yes)
			(layer "F.Fab")
			(hide yes)
			(effects
				(font
					(size 1.016 1.016)
					(thickness 0.1524)
				)
			)
		)
		(duplicate_pad_numbers_are_jumpers no)
		(fp_line
			(start 0.889 -1.7018)
			(end 0.889 1.7018)
			(stroke
				(width 0.1524)
				(type default)
			)
			(layer "F.SilkS")
		)
		(fp_line
			(start -0.889 -1.7018)
			(end 0.889 -1.7018)
			(stroke
				(width 0.1524)
				(type default)
			)
			(layer "F.SilkS")
		)
		(fp_line
			(start 0.889 1.7018)
			(end -0.889 1.7018)
			(stroke
				(width 0.1524)
				(type default)
			)
			(layer "F.SilkS")
		)
		(fp_line
			(start -0.889 1.7018)
			(end -0.889 -1.7018)
			(stroke
				(width 0.1524)
				(type default)
			)
			(layer "F.SilkS")
		)
		(fp_rect
			(start -0.9652 1.778)
			(end 0.9652 -1.778)
			(stroke
				(width 0)
				(type default)
			)
			(fill no)
			(layer "F.CrtYd")
		)
		(fp_rect
			(start -0.9652 1.778)
			(end 0.9652 -1.778)
			(stroke
				(width 0)
				(type default)
			)
			(fill no)
			(layer "F.Fab")
		)
		(pad "1" smd rect
			(at 0 -0.9652 90)
			(size 1.397 1.143)
			(layers "F.Cu" "F.Mask" "F.Paste")
			(net "P0V9")
		)
		(pad "2" smd rect
			(at 0 0.9652 90)
			(size 1.397 1.143)
			(layers "F.Cu" "F.Mask" "F.Paste")
			(net "GB_VDDA")
		)
	)
	(footprint ""
		(layer "F.Cu")
		(at 134.52221 -85.262466 -90)
		(property "Reference" "R62"
			(at 0 0 270)
			(layer "F.SilkS")
			(hide yes)
			(effects
				(font
					(size 1.27 1.27)
				)
			)
		)
		(property "Value" "1KR2F-3-GP"
			(at 0.064008 -3.993896 270)
			(unlocked yes)
			(layer "F.Fab")
			(hide yes)
			(effects
				(font
					(size 1.016 1.016)
					(thickness 0.1524)
				)
			)
		)
		(property "Device Type" "R402H16"
			(at 0.064008 -5.517896 270)
			(unlocked yes)
			(layer "F.Fab")
			(hide yes)
			(effects
				(font
					(size 1.016 1.016)
					(thickness 0.1524)
				)
			)
		)
		(duplicate_pad_numbers_are_jumpers no)
		(fp_line
			(start -0.508 -0.9398)
			(end -0.508 0.9398)
			(stroke
				(width 0.1524)
				(type default)
			)
			(layer "F.SilkS")
		)
		(fp_line
			(start 0.508 -0.9398)
			(end -0.508 -0.9398)
			(stroke
				(width 0.1524)
				(type default)
			)
			(layer "F.SilkS")
		)
		(fp_rect
			(start -0.508 0.9398)
			(end 0.508 -0.9398)
			(stroke
				(width 0)
				(type default)
			)
			(fill no)
			(layer "F.CrtYd")
		)
		(fp_rect
			(start -0.508 0.9398)
			(end 0.508 -0.9398)
			(stroke
				(width 0)
				(type default)
			)
			(fill no)
			(layer "F.Fab")
		)
		(pad "1" smd custom
			(at 0 -0.4445 270)
			(size 0.1397 0.1397)
			(layers "F.Cu" "F.Mask" "F.Paste")
			(net "P1V8_E")
			(options
				(clearance outline)
				(anchor circle)
			)
			(primitives
				(gr_poly
					(pts
						(arc
							(start -0.1778 -0.2794)
							(mid -0.249642 -0.249642)
							(end -0.2794 -0.1778)
						)
						(arc
							(start -0.2794 0.1778)
							(mid -0.249642 0.249642)
							(end -0.1778 0.2794)
						)
						(arc
							(start 0.1778 0.2794)
							(mid 0.249642 0.249642)
							(end 0.2794 0.1778)
						)
						(arc
							(start 0.2794 -0.1778)
							(mid 0.249642 -0.249642)
							(end 0.1778 -0.2794)
						)
					)
					(width 0)
					(fill yes)
				)
			)
		)
		(pad "2" smd custom
			(at 0 0.4445 270)
			(size 0.1397 0.1397)
			(layers "F.Cu" "F.Mask" "F.Paste")
			(net "I2C_EXP_IOC_SCL8")
			(options
				(clearance outline)
				(anchor circle)
			)
			(primitives
				(gr_poly
					(pts
						(arc
							(start -0.1778 -0.2794)
							(mid -0.249642 -0.249642)
							(end -0.2794 -0.1778)
						)
						(arc
							(start -0.2794 0.1778)
							(mid -0.249642 0.249642)
							(end -0.1778 0.2794)
						)
						(arc
							(start 0.1778 0.2794)
							(mid 0.249642 0.249642)
							(end 0.2794 0.1778)
						)
						(arc
							(start 0.2794 -0.1778)
							(mid 0.249642 -0.249642)
							(end 0.1778 -0.2794)
						)
					)
					(width 0)
					(fill yes)
				)
			)
		)
	)
	(footprint ""
		(layer "F.Cu")
		(at 63.700914 -17.126458 180)
		(property "Reference" "R75"
			(at 0 0 180)
			(layer "F.SilkS")
			(hide yes)
			(effects
				(font
					(size 1.27 1.27)
				)
			)
		)
		(property "Value" "0R2J-2-GP"
			(at 0.064008 -3.993896 180)
			(unlocked yes)
			(layer "F.Fab")
			(hide yes)
			(effects
				(font
					(size 1.016 1.016)
					(thickness 0.1524)
				)
			)
		)
		(property "Device Type" "R402H16"
			(at 0.064008 -5.517896 180)
			(unlocked yes)
			(layer "F.Fab")
			(hide yes)
			(effects
				(font
					(size 1.016 1.016)
					(thickness 0.1524)
				)
			)
		)
		(duplicate_pad_numbers_are_jumpers no)
		(fp_line
			(start 0.508 -0.9398)
			(end -0.508 -0.9398)
			(stroke
				(width 0.1524)
				(type default)
			)
			(layer "F.SilkS")
		)
		(fp_line
			(start -0.508 -0.9398)
			(end -0.508 0.9398)
			(stroke
				(width 0.1524)
				(type default)
			)
			(layer "F.SilkS")
		)
		(fp_rect
			(start -0.508 0.9398)
			(end 0.508 -0.9398)
			(stroke
				(width 0)
				(type default)
			)
			(fill no)
			(layer "F.CrtYd")
		)
		(fp_rect
			(start -0.508 0.9398)
			(end 0.508 -0.9398)
			(stroke
				(width 0)
				(type default)
			)
			(fill no)
			(layer "F.Fab")
		)
		(pad "1" smd custom
			(at 0 -0.4445 180)
			(size 0.1397 0.1397)
			(layers "F.Cu" "F.Mask" "F.Paste")
			(net "LS_EN_U14")
			(options
				(clearance outline)
				(anchor circle)
			)
			(primitives
				(gr_poly
					(pts
						(arc
							(start -0.1778 -0.2794)
							(mid -0.249642 -0.249642)
							(end -0.2794 -0.1778)
						)
						(arc
							(start -0.2794 0.1778)
							(mid -0.249642 0.249642)
							(end -0.1778 0.2794)
						)
						(arc
							(start 0.1778 0.2794)
							(mid 0.249642 0.249642)
							(end 0.2794 0.1778)
						)
						(arc
							(start 0.2794 -0.1778)
							(mid 0.249642 -0.249642)
							(end 0.1778 -0.2794)
						)
					)
					(width 0)
					(fill yes)
				)
			)
		)
		(pad "2" smd custom
			(at 0 0.4445 180)
			(size 0.1397 0.1397)
			(layers "F.Cu" "F.Mask" "F.Paste")
			(net "LS_EN_N")
			(options
				(clearance outline)
				(anchor circle)
			)
			(primitives
				(gr_poly
					(pts
						(arc
							(start -0.1778 -0.2794)
							(mid -0.249642 -0.249642)
							(end -0.2794 -0.1778)
						)
						(arc
							(start -0.2794 0.1778)
							(mid -0.249642 0.249642)
							(end -0.1778 0.2794)
						)
						(arc
							(start 0.1778 0.2794)
							(mid 0.249642 0.249642)
							(end 0.2794 0.1778)
						)
						(arc
							(start 0.2794 -0.1778)
							(mid 0.249642 -0.249642)
							(end 0.1778 -0.2794)
						)
					)
					(width 0)
					(fill yes)
				)
			)
		)
	)
)
